(kicad_pcb
	(version 20260206)
	(generator "pcbnew")
	(generator_version "10.0")
	(general
		(thickness 1.6)
		(legacy_teardrops no)
	)
	(paper "A4")
	(title_block
		(title "04192023_DAF0TMB3IC0_F0TG_MB_C_brd_V02_OCP.brd")
		(comment 1 "Grand Teton / footprints 5891-5896 of 8354")
	)
	(layers
		(0 "F.Cu" signal "TOP")
		(4 "In1.Cu" signal "GND")
		(6 "In2.Cu" signal "IN1")
		(8 "In3.Cu" signal "GND1")
		(10 "In4.Cu" signal "IN2")
		(12 "In5.Cu" signal "GND2")
		(14 "In6.Cu" signal "IN3")
		(16 "In7.Cu" signal "GND3")
		(18 "In8.Cu" signal "VCC")
		(20 "In9.Cu" signal "VCC1")
		(22 "In10.Cu" signal "GND4")
		(24 "In11.Cu" signal "IN4")
		(26 "In12.Cu" signal "GND5")
		(28 "In13.Cu" signal "IN5")
		(30 "In14.Cu" signal "GND6")
		(32 "In15.Cu" signal "IN6")
		(34 "In16.Cu" signal "GND7")
		(2 "B.Cu" signal "BOTTOM")
		(9 "F.Adhes" user "F.Adhesive")
		(11 "B.Adhes" user "B.Adhesive")
		(13 "F.Paste" user "Package Geometry/Pastemask Top")
		(15 "B.Paste" user "Package Geometry/Pastemask Bottom")
		(5 "F.SilkS" user "Ref Des/Silkscreen Top")
		(7 "B.SilkS" user "Ref Des/Silkscreen Bottom")
		(1 "F.Mask" user "Board Geometry/Soldermask Top")
		(3 "B.Mask" user "Board Geometry/Soldermask Bottom")
		(17 "Dwgs.User" user "User.Drawings")
		(19 "Cmts.User" user "User.Comments")
		(21 "Eco1.User" user "User.Eco1")
		(23 "Eco2.User" user "User.Eco2")
		(25 "Edge.Cuts" user "Board Geometry/Outline")
		(27 "Margin" user)
		(31 "F.CrtYd" user "Package Geometry/Place Bound Top")
		(29 "B.CrtYd" user "Package Geometry/Place Bound Bottom")
		(35 "F.Fab" user "Ref Des/Assembly Top")
		(33 "B.Fab" user "Ref Des/Assembly Bottom")
	)
	(footprint ""
		(layer "B.Cu")
		(at 197.269608 -108.545376)
		(property "Reference" "R286"
			(at 0 0 0)
			(layer "B.SilkS")
			(hide yes)
			(effects
				(font
					(size 1.27 1.27)
				)
				(justify mirror)
			)
		)
		(property "Value" ""
			(at 0 0 0)
			(layer "B.Fab")
			(effects
				(font
					(size 1.27 1.27)
				)
				(justify mirror)
			)
		)
		(duplicate_pad_numbers_are_jumpers no)
		(fp_line
			(start -0.7874 -0.4064)
			(end -0.7874 0.4064)
			(stroke
				(width 0.1524)
				(type default)
			)
			(layer "B.SilkS")
		)
		(fp_line
			(start -0.7874 0.4064)
			(end 0.7874 0.4064)
			(stroke
				(width 0.1524)
				(type default)
			)
			(layer "B.SilkS")
		)
		(fp_line
			(start 0.7874 -0.4064)
			(end -0.7874 -0.4064)
			(stroke
				(width 0.1524)
				(type default)
			)
			(layer "B.SilkS")
		)
		(fp_line
			(start 0.7874 0.4064)
			(end 0.7874 -0.4064)
			(stroke
				(width 0.1524)
				(type default)
			)
			(layer "B.SilkS")
		)
		(fp_line
			(start -0.67945 -0.3048)
			(end -0.67945 0.3048)
			(stroke
				(width 0.1)
				(type default)
			)
			(layer "B.Fab")
		)
		(fp_line
			(start -0.67945 0.3048)
			(end -0.120396 0.3048)
			(stroke
				(width 0.1)
				(type default)
			)
			(layer "B.Fab")
		)
		(fp_line
			(start -0.12065 -0.3048)
			(end -0.67945 -0.3048)
			(stroke
				(width 0.1)
				(type default)
			)
			(layer "B.Fab")
		)
		(fp_line
			(start -0.12065 -0.2794)
			(end -0.12065 -0.3048)
			(stroke
				(width 0.1)
				(type default)
			)
			(layer "B.Fab")
		)
		(fp_line
			(start -0.120396 0.2794)
			(end 0.12065 0.2794)
			(stroke
				(width 0.1)
				(type default)
			)
			(layer "B.Fab")
		)
		(fp_line
			(start -0.120396 0.3048)
			(end -0.120396 0.2794)
			(stroke
				(width 0.1)
				(type default)
			)
			(layer "B.Fab")
		)
		(fp_line
			(start 0.12065 -0.305054)
			(end 0.12065 -0.2794)
			(stroke
				(width 0.1)
				(type default)
			)
			(layer "B.Fab")
		)
		(fp_line
			(start 0.12065 -0.2794)
			(end -0.12065 -0.2794)
			(stroke
				(width 0.1)
				(type default)
			)
			(layer "B.Fab")
		)
		(fp_line
			(start 0.12065 0.2794)
			(end 0.12065 0.3048)
			(stroke
				(width 0.1)
				(type default)
			)
			(layer "B.Fab")
		)
		(fp_line
			(start 0.12065 0.3048)
			(end 0.67945 0.3048)
			(stroke
				(width 0.1)
				(type default)
			)
			(layer "B.Fab")
		)
		(fp_line
			(start 0.67945 -0.305054)
			(end 0.12065 -0.305054)
			(stroke
				(width 0.1)
				(type default)
			)
			(layer "B.Fab")
		)
		(fp_line
			(start 0.67945 0.3048)
			(end 0.67945 -0.305054)
			(stroke
				(width 0.1)
				(type default)
			)
			(layer "B.Fab")
		)
		(pad "1" smd circle
			(at 0.40005 0 180)
			(size 0 0)
			(layers "B.Cu" "B.Mask" "B.Paste")
			(net "PWRGD_PVDDCR_CPU1_P1")
		)
		(pad "2" smd circle
			(at -0.40005 0 180)
			(size 0 0)
			(layers "B.Cu" "B.Mask" "B.Paste")
			(net "FM_PWRGD_PVDDCR_CPU1_P1")
		)
	)
	(footprint ""
		(layer "B.Cu")
		(at 430.80051 -193.99631)
		(property "Reference" "C124"
			(at 0 0 0)
			(layer "B.SilkS")
			(hide yes)
			(effects
				(font
					(size 1.27 1.27)
				)
				(justify mirror)
			)
		)
		(property "Value" ""
			(at 0 0 0)
			(layer "B.Fab")
			(effects
				(font
					(size 1.27 1.27)
				)
				(justify mirror)
			)
		)
		(duplicate_pad_numbers_are_jumpers no)
		(fp_line
			(start -0.7874 -0.4064)
			(end -0.7874 0.4064)
			(stroke
				(width 0.1524)
				(type default)
			)
			(layer "B.SilkS")
		)
		(fp_line
			(start -0.7874 0.4064)
			(end 0.7874 0.4064)
			(stroke
				(width 0.1524)
				(type default)
			)
			(layer "B.SilkS")
		)
		(fp_line
			(start 0.7874 -0.4064)
			(end -0.7874 -0.4064)
			(stroke
				(width 0.1524)
				(type default)
			)
			(layer "B.SilkS")
		)
		(fp_line
			(start 0.7874 0.4064)
			(end 0.7874 -0.4064)
			(stroke
				(width 0.1524)
				(type default)
			)
			(layer "B.SilkS")
		)
		(fp_line
			(start -0.67945 -0.3048)
			(end -0.67945 0.3048)
			(stroke
				(width 0.1)
				(type default)
			)
			(layer "B.Fab")
		)
		(fp_line
			(start -0.67945 0.3048)
			(end -0.120396 0.3048)
			(stroke
				(width 0.1)
				(type default)
			)
			(layer "B.Fab")
		)
		(fp_line
			(start -0.12065 -0.3048)
			(end -0.67945 -0.3048)
			(stroke
				(width 0.1)
				(type default)
			)
			(layer "B.Fab")
		)
		(fp_line
			(start -0.12065 -0.2794)
			(end -0.12065 -0.3048)
			(stroke
				(width 0.1)
				(type default)
			)
			(layer "B.Fab")
		)
		(fp_line
			(start -0.120396 0.2794)
			(end 0.12065 0.2794)
			(stroke
				(width 0.1)
				(type default)
			)
			(layer "B.Fab")
		)
		(fp_line
			(start -0.120396 0.3048)
			(end -0.120396 0.2794)
			(stroke
				(width 0.1)
				(type default)
			)
			(layer "B.Fab")
		)
		(fp_line
			(start 0.12065 -0.305054)
			(end 0.12065 -0.2794)
			(stroke
				(width 0.1)
				(type default)
			)
			(layer "B.Fab")
		)
		(fp_line
			(start 0.12065 -0.2794)
			(end -0.12065 -0.2794)
			(stroke
				(width 0.1)
				(type default)
			)
			(layer "B.Fab")
		)
		(fp_line
			(start 0.12065 0.2794)
			(end 0.12065 0.3048)
			(stroke
				(width 0.1)
				(type default)
			)
			(layer "B.Fab")
		)
		(fp_line
			(start 0.12065 0.3048)
			(end 0.67945 0.3048)
			(stroke
				(width 0.1)
				(type default)
			)
			(layer "B.Fab")
		)
		(fp_line
			(start 0.67945 -0.305054)
			(end 0.12065 -0.305054)
			(stroke
				(width 0.1)
				(type default)
			)
			(layer "B.Fab")
		)
		(fp_line
			(start 0.67945 0.3048)
			(end 0.67945 -0.305054)
			(stroke
				(width 0.1)
				(type default)
			)
			(layer "B.Fab")
		)
		(pad "1" smd circle
			(at 0.40005 0 180)
			(size 0 0)
			(layers "B.Cu" "B.Mask" "B.Paste")
			(net "P3V3_AUX")
		)
		(pad "2" smd circle
			(at -0.40005 0 180)
			(size 0 0)
			(layers "B.Cu" "B.Mask" "B.Paste")
			(net "GND")
		)
	)
	(footprint ""
		(layer "B.Cu")
		(at 439.782966 -425.184824 -90)
		(property "Reference" "PR6616"
			(at 0 0 90)
			(layer "B.SilkS")
			(hide yes)
			(effects
				(font
					(size 1.27 1.27)
				)
				(justify mirror)
			)
		)
		(property "Value" ""
			(at 0 0 90)
			(layer "B.Fab")
			(effects
				(font
					(size 1.27 1.27)
				)
				(justify mirror)
			)
		)
		(duplicate_pad_numbers_are_jumpers no)
		(fp_line
			(start -0.7874 0.4064)
			(end 0.7874 0.4064)
			(stroke
				(width 0.1524)
				(type default)
			)
			(layer "B.SilkS")
		)
		(fp_line
			(start 0.7874 0.4064)
			(end 0.7874 -0.4064)
			(stroke
				(width 0.1524)
				(type default)
			)
			(layer "B.SilkS")
		)
		(fp_line
			(start -0.7874 -0.4064)
			(end -0.7874 0.4064)
			(stroke
				(width 0.1524)
				(type default)
			)
			(layer "B.SilkS")
		)
		(fp_line
			(start 0.7874 -0.4064)
			(end -0.7874 -0.4064)
			(stroke
				(width 0.1524)
				(type default)
			)
			(layer "B.SilkS")
		)
		(fp_line
			(start -0.67945 0.3048)
			(end -0.120396 0.3048)
			(stroke
				(width 0.1)
				(type default)
			)
			(layer "B.Fab")
		)
		(fp_line
			(start -0.120396 0.3048)
			(end -0.120396 0.2794)
			(stroke
				(width 0.1)
				(type default)
			)
			(layer "B.Fab")
		)
		(fp_line
			(start 0.12065 0.3048)
			(end 0.67945 0.3048)
			(stroke
				(width 0.1)
				(type default)
			)
			(layer "B.Fab")
		)
		(fp_line
			(start 0.67945 0.3048)
			(end 0.67945 -0.305054)
			(stroke
				(width 0.1)
				(type default)
			)
			(layer "B.Fab")
		)
		(fp_line
			(start -0.120396 0.2794)
			(end 0.12065 0.2794)
			(stroke
				(width 0.1)
				(type default)
			)
			(layer "B.Fab")
		)
		(fp_line
			(start 0.12065 0.2794)
			(end 0.12065 0.3048)
			(stroke
				(width 0.1)
				(type default)
			)
			(layer "B.Fab")
		)
		(fp_line
			(start -0.12065 -0.2794)
			(end -0.12065 -0.3048)
			(stroke
				(width 0.1)
				(type default)
			)
			(layer "B.Fab")
		)
		(fp_line
			(start 0.12065 -0.2794)
			(end -0.12065 -0.2794)
			(stroke
				(width 0.1)
				(type default)
			)
			(layer "B.Fab")
		)
		(fp_line
			(start -0.67945 -0.3048)
			(end -0.67945 0.3048)
			(stroke
				(width 0.1)
				(type default)
			)
			(layer "B.Fab")
		)
		(fp_line
			(start -0.12065 -0.3048)
			(end -0.67945 -0.3048)
			(stroke
				(width 0.1)
				(type default)
			)
			(layer "B.Fab")
		)
		(fp_line
			(start 0.12065 -0.305054)
			(end 0.12065 -0.2794)
			(stroke
				(width 0.1)
				(type default)
			)
			(layer "B.Fab")
		)
		(fp_line
			(start 0.67945 -0.305054)
			(end 0.12065 -0.305054)
			(stroke
				(width 0.1)
				(type default)
			)
			(layer "B.Fab")
		)
		(pad "1" smd circle
			(at 0.40005 0 90)
			(size 0 0)
			(layers "B.Cu" "B.Mask" "B.Paste")
			(net "P0V9_RETIMER_CPU0_VRHOT")
		)
		(pad "2" smd circle
			(at -0.40005 0 90)
			(size 0 0)
			(layers "B.Cu" "B.Mask" "B.Paste")
			(net "TP_P0V9_RETIMER_CPU0_VRHOT")
		)
	)
	(footprint ""
		(layer "B.Cu")
		(at 329.806046 -416.899344 90)
		(property "Reference" "C6550"
			(at 0 0 90)
			(layer "B.SilkS")
			(hide yes)
			(effects
				(font
					(size 1.27 1.27)
				)
				(justify mirror)
			)
		)
		(property "Value" ""
			(at 0 0 90)
			(layer "B.Fab")
			(effects
				(font
					(size 1.27 1.27)
				)
				(justify mirror)
			)
		)
		(duplicate_pad_numbers_are_jumpers no)
		(fp_line
			(start 0.299974 -0.150114)
			(end -0.299974 -0.150114)
			(stroke
				(width 0.1)
				(type default)
			)
			(layer "B.Fab")
		)
		(fp_line
			(start -0.299974 -0.150114)
			(end -0.299974 0.150114)
			(stroke
				(width 0.1)
				(type default)
			)
			(layer "B.Fab")
		)
		(fp_line
			(start 0.299974 0.150114)
			(end 0.299974 -0.150114)
			(stroke
				(width 0.1)
				(type default)
			)
			(layer "B.Fab")
		)
		(fp_line
			(start -0.299974 0.150114)
			(end 0.299974 0.150114)
			(stroke
				(width 0.1)
				(type default)
			)
			(layer "B.Fab")
		)
		(pad "1" smd rect
			(at 0.2667 0 270)
			(size 0.3048 0.381)
			(layers "B.Cu" "B.Mask" "B.Paste")
			(net "P5E_CPU0_P1_TX_BUF_C_DN<8>")
		)
		(pad "2" smd rect
			(at -0.2667 0 270)
			(size 0.3048 0.381)
			(layers "B.Cu" "B.Mask" "B.Paste")
			(net "P5E_CPU0_P1_TX_BUF_DN<8>")
		)
	)
	(footprint ""
		(layer "B.Cu")
		(at 182.860696 -194.8942 180)
		(property "Reference" "R1588"
			(at 0 0 0)
			(layer "B.SilkS")
			(hide yes)
			(effects
				(font
					(size 1.27 1.27)
				)
				(justify mirror)
			)
		)
		(property "Value" ""
			(at 0 0 0)
			(layer "B.Fab")
			(effects
				(font
					(size 1.27 1.27)
				)
				(justify mirror)
			)
		)
		(duplicate_pad_numbers_are_jumpers no)
		(fp_line
			(start 0.7874 0.4064)
			(end 0.7874 -0.4064)
			(stroke
				(width 0.1524)
				(type default)
			)
			(layer "B.SilkS")
		)
		(fp_line
			(start 0.7874 -0.4064)
			(end -0.7874 -0.4064)
			(stroke
				(width 0.1524)
				(type default)
			)
			(layer "B.SilkS")
		)
		(fp_line
			(start -0.7874 0.4064)
			(end 0.7874 0.4064)
			(stroke
				(width 0.1524)
				(type default)
			)
			(layer "B.SilkS")
		)
		(fp_line
			(start -0.7874 -0.4064)
			(end -0.7874 0.4064)
			(stroke
				(width 0.1524)
				(type default)
			)
			(layer "B.SilkS")
		)
		(fp_line
			(start 0.67945 0.3048)
			(end 0.67945 -0.305054)
			(stroke
				(width 0.1)
				(type default)
			)
			(layer "B.Fab")
		)
		(fp_line
			(start 0.67945 -0.305054)
			(end 0.12065 -0.305054)
			(stroke
				(width 0.1)
				(type default)
			)
			(layer "B.Fab")
		)
		(fp_line
			(start 0.12065 0.3048)
			(end 0.67945 0.3048)
			(stroke
				(width 0.1)
				(type default)
			)
			(layer "B.Fab")
		)
		(fp_line
			(start 0.12065 0.2794)
			(end 0.12065 0.3048)
			(stroke
				(width 0.1)
				(type default)
			)
			(layer "B.Fab")
		)
		(fp_line
			(start 0.12065 -0.2794)
			(end -0.12065 -0.2794)
			(stroke
				(width 0.1)
				(type default)
			)
			(layer "B.Fab")
		)
		(fp_line
			(start 0.12065 -0.305054)
			(end 0.12065 -0.2794)
			(stroke
				(width 0.1)
				(type default)
			)
			(layer "B.Fab")
		)
		(fp_line
			(start -0.120396 0.3048)
			(end -0.120396 0.2794)
			(stroke
				(width 0.1)
				(type default)
			)
			(layer "B.Fab")
		)
		(fp_line
			(start -0.120396 0.2794)
			(end 0.12065 0.2794)
			(stroke
				(width 0.1)
				(type default)
			)
			(layer "B.Fab")
		)
		(fp_line
			(start -0.12065 -0.2794)
			(end -0.12065 -0.3048)
			(stroke
				(width 0.1)
				(type default)
			)
			(layer "B.Fab")
		)
		(fp_line
			(start -0.12065 -0.3048)
			(end -0.67945 -0.3048)
			(stroke
				(width 0.1)
				(type default)
			)
			(layer "B.Fab")
		)
		(fp_line
			(start -0.67945 0.3048)
			(end -0.120396 0.3048)
			(stroke
				(width 0.1)
				(type default)
			)
			(layer "B.Fab")
		)
		(fp_line
			(start -0.67945 -0.3048)
			(end -0.67945 0.3048)
			(stroke
				(width 0.1)
				(type default)
			)
			(layer "B.Fab")
		)
		(pad "1" smd circle
			(at 0.40005 0)
			(size 0 0)
			(layers "B.Cu" "B.Mask" "B.Paste")
			(net "I3C_SPD_DDRGL_CPU1_SCL")
		)
		(pad "2" smd circle
			(at -0.40005 0)
			(size 0 0)
			(layers "B.Cu" "B.Mask" "B.Paste")
			(net "I3C_SPD_DDRI_CPU1_SCL")
		)
	)
	(footprint ""
		(layer "B.Cu")
		(at 153.990802 -16.851122 -90)
		(property "Reference" "R3226"
			(at 0 0 90)
			(layer "B.SilkS")
			(hide yes)
			(effects
				(font
					(size 1.27 1.27)
				)
				(justify mirror)
			)
		)
		(property "Value" ""
			(at 0 0 90)
			(layer "B.Fab")
			(effects
				(font
					(size 1.27 1.27)
				)
				(justify mirror)
			)
		)
		(duplicate_pad_numbers_are_jumpers no)
		(fp_line
			(start -0.7874 0.4064)
			(end 0.7874 0.4064)
			(stroke
				(width 0.1524)
				(type default)
			)
			(layer "B.SilkS")
		)
		(fp_line
			(start 0.7874 0.4064)
			(end 0.7874 -0.4064)
			(stroke
				(width 0.1524)
				(type default)
			)
			(layer "B.SilkS")
		)
		(fp_line
			(start -0.7874 -0.4064)
			(end -0.7874 0.4064)
			(stroke
				(width 0.1524)
				(type default)
			)
			(layer "B.SilkS")
		)
		(fp_line
			(start 0.7874 -0.4064)
			(end -0.7874 -0.4064)
			(stroke
				(width 0.1524)
				(type default)
			)
			(layer "B.SilkS")
		)
		(fp_line
			(start -0.67945 0.3048)
			(end -0.120396 0.3048)
			(stroke
				(width 0.1)
				(type default)
			)
			(layer "B.Fab")
		)
		(fp_line
			(start -0.120396 0.3048)
			(end -0.120396 0.2794)
			(stroke
				(width 0.1)
				(type default)
			)
			(layer "B.Fab")
		)
		(fp_line
			(start 0.12065 0.3048)
			(end 0.67945 0.3048)
			(stroke
				(width 0.1)
				(type default)
			)
			(layer "B.Fab")
		)
		(fp_line
			(start 0.67945 0.3048)
			(end 0.67945 -0.305054)
			(stroke
				(width 0.1)
				(type default)
			)
			(layer "B.Fab")
		)
		(fp_line
			(start -0.120396 0.2794)
			(end 0.12065 0.2794)
			(stroke
				(width 0.1)
				(type default)
			)
			(layer "B.Fab")
		)
		(fp_line
			(start 0.12065 0.2794)
			(end 0.12065 0.3048)
			(stroke
				(width 0.1)
				(type default)
			)
			(layer "B.Fab")
		)
		(fp_line
			(start -0.12065 -0.2794)
			(end -0.12065 -0.3048)
			(stroke
				(width 0.1)
				(type default)
			)
			(layer "B.Fab")
		)
		(fp_line
			(start 0.12065 -0.2794)
			(end -0.12065 -0.2794)
			(stroke
				(width 0.1)
				(type default)
			)
			(layer "B.Fab")
		)
		(fp_line
			(start -0.67945 -0.3048)
			(end -0.67945 0.3048)
			(stroke
				(width 0.1)
				(type default)
			)
			(layer "B.Fab")
		)
		(fp_line
			(start -0.12065 -0.3048)
			(end -0.67945 -0.3048)
			(stroke
				(width 0.1)
				(type default)
			)
			(layer "B.Fab")
		)
		(fp_line
			(start 0.12065 -0.305054)
			(end 0.12065 -0.2794)
			(stroke
				(width 0.1)
				(type default)
			)
			(layer "B.Fab")
		)
		(fp_line
			(start 0.67945 -0.305054)
			(end 0.12065 -0.305054)
			(stroke
				(width 0.1)
				(type default)
			)
			(layer "B.Fab")
		)
		(pad "1" smd circle
			(at 0.40005 0 90)
			(size 0 0)
			(layers "B.Cu" "B.Mask" "B.Paste")
			(net "SMB_1_BMC_GPU_SCL")
		)
		(pad "2" smd circle
			(at -0.40005 0 90)
			(size 0 0)
			(layers "B.Cu" "B.Mask" "B.Paste")
			(net "P3V3_AUX")
		)
	)
)
